(kicad_pcb
	(version 20260206)
	(generator "pcbnew")
	(generator_version "10.0")
	(general
		(thickness 1.6)
		(legacy_teardrops no)
	)
	(paper "A4")
	(title_block
		(title "pdpb — Lightning_PDPB_BRD.brd")
		(comment 1 "Lightning (Wiwynn / Facebook NVMe JBOF) / footprints 871-871 of 1140")
	)
	(layers
		(0 "F.Cu" signal "TOP")
		(4 "In1.Cu" signal "L2GND")
		(6 "In2.Cu" signal "L3")
		(8 "In3.Cu" signal "L4VCC")
		(10 "In4.Cu" signal "L5VCC")
		(12 "In5.Cu" signal "L6")
		(14 "In6.Cu" signal "L7GND")
		(2 "B.Cu" signal "BOTTOM")
		(9 "F.Adhes" user "F.Adhesive")
		(11 "B.Adhes" user "B.Adhesive")
		(13 "F.Paste" user "Package Geometry/Pastemask Top")
		(15 "B.Paste" user "Package Geometry/Pastemask Bottom")
		(5 "F.SilkS" user "Ref Des/Silkscreen Top")
		(7 "B.SilkS" user "Ref Des/Silkscreen Bottom")
		(1 "F.Mask" user "Board Geometry/Soldermask Top")
		(3 "B.Mask" user "Board Geometry/Soldermask Bottom")
		(17 "Dwgs.User" user "User.Drawings")
		(19 "Cmts.User" user "User.Comments")
		(21 "Eco1.User" user "User.Eco1")
		(23 "Eco2.User" user "User.Eco2")
		(25 "Edge.Cuts" user "Board Geometry/Outline")
		(27 "Margin" user)
		(31 "F.CrtYd" user "Package Geometry/Place Bound Top")
		(29 "B.CrtYd" user "Package Geometry/Place Bound Bottom")
		(35 "F.Fab" user "Ref Des/Assembly Top")
		(33 "B.Fab" user "Ref Des/Assembly Bottom")
	)
	(footprint ""
		(layer "F.Cu")
		(at 20.850098 -438.330086 -90)
		(property "Reference" "J10"
			(at 0 0 270)
			(layer "F.SilkS")
			(hide yes)
			(effects
				(font
					(size 1.27 1.27)
				)
			)
		)
		(property "Value" "PCISLT68-14-GP-U1"
			(at -22.225 12.7508 270)
			(unlocked yes)
			(layer "F.Fab")
			(hide yes)
			(effects
				(font
					(size 1.016 1.016)
					(thickness 0.1524)
				)
			)
		)
		(property "Device Type" "SD-78827-0001"
			(at -22.225 11.2268 270)
			(unlocked yes)
			(layer "F.Fab")
			(hide yes)
			(effects
				(font
					(size 1.016 1.016)
					(thickness 0.1524)
				)
			)
		)
		(duplicate_pad_numbers_are_jumpers no)
		(fp_line
			(start -20.4724 12.0142)
			(end -20.4724 4.6736)
			(stroke
				(width 0.1524)
				(type default)
			)
			(layer "F.SilkS")
		)
		(fp_line
			(start -17.8435 12.0142)
			(end -20.4724 12.0142)
			(stroke
				(width 0.1524)
				(type default)
			)
			(layer "F.SilkS")
		)
		(fp_line
			(start 17.8435 12.0142)
			(end 17.8435 10.3124)
			(stroke
				(width 0.1524)
				(type default)
			)
			(layer "F.SilkS")
		)
		(fp_line
			(start 20.4724 12.0142)
			(end 17.8435 12.0142)
			(stroke
				(width 0.1524)
				(type default)
			)
			(layer "F.SilkS")
		)
		(fp_line
			(start -17.8435 10.3124)
			(end -17.8435 12.0142)
			(stroke
				(width 0.1524)
				(type default)
			)
			(layer "F.SilkS")
		)
		(fp_line
			(start 17.8435 10.3124)
			(end -17.8435 10.3124)
			(stroke
				(width 0.1524)
				(type default)
			)
			(layer "F.SilkS")
		)
		(fp_line
			(start -23.749 4.6736)
			(end -23.749 0.0254)
			(stroke
				(width 0.1524)
				(type default)
			)
			(layer "F.SilkS")
		)
		(fp_line
			(start -20.4724 4.6736)
			(end -23.749 4.6736)
			(stroke
				(width 0.1524)
				(type default)
			)
			(layer "F.SilkS")
		)
		(fp_line
			(start 20.4724 4.6736)
			(end 20.4724 12.0142)
			(stroke
				(width 0.1524)
				(type default)
			)
			(layer "F.SilkS")
		)
		(fp_line
			(start 23.749 4.6736)
			(end 20.4724 4.6736)
			(stroke
				(width 0.1524)
				(type default)
			)
			(layer "F.SilkS")
		)
		(fp_line
			(start -23.117556 2.896108)
			(end -23.117556 1.803908)
			(stroke
				(width 0.3048)
				(type default)
			)
			(layer "F.SilkS")
		)
		(fp_line
			(start 20.882356 2.896108)
			(end 20.882356 1.803908)
			(stroke
				(width 0.3048)
				(type default)
			)
			(layer "F.SilkS")
		)
		(fp_line
			(start -20.882356 1.803908)
			(end -20.882356 2.896108)
			(stroke
				(width 0.3048)
				(type default)
			)
			(layer "F.SilkS")
		)
		(fp_line
			(start 23.117556 1.803908)
			(end 23.117556 2.896108)
			(stroke
				(width 0.3048)
				(type default)
			)
			(layer "F.SilkS")
		)
		(fp_line
			(start -23.749 0.0254)
			(end -20.4724 0.0254)
			(stroke
				(width 0.1524)
				(type default)
			)
			(layer "F.SilkS")
		)
		(fp_line
			(start -20.4724 0.0254)
			(end -20.4724 -3.4036)
			(stroke
				(width 0.1524)
				(type default)
			)
			(layer "F.SilkS")
		)
		(fp_line
			(start 20.4724 0.0254)
			(end 23.749 0.0254)
			(stroke
				(width 0.1524)
				(type default)
			)
			(layer "F.SilkS")
		)
		(fp_line
			(start 23.749 0.0254)
			(end 23.749 4.6736)
			(stroke
				(width 0.1524)
				(type default)
			)
			(layer "F.SilkS")
		)
		(fp_line
			(start -20.4724 -3.4036)
			(end 20.4724 -3.4036)
			(stroke
				(width 0.1524)
				(type default)
			)
			(layer "F.SilkS")
		)
		(fp_line
			(start 20.4724 -3.4036)
			(end 20.4724 0.0254)
			(stroke
				(width 0.1524)
				(type default)
			)
			(layer "F.SilkS")
		)
		(fp_arc
			(start -20.882356 2.896108)
			(mid -21.999956 4.013708)
			(end -23.117556 2.896108)
			(stroke
				(width 0.3048)
				(type default)
			)
			(layer "F.SilkS")
		)
		(fp_arc
			(start 23.117556 2.896108)
			(mid 21.999956 4.013708)
			(end 20.882356 2.896108)
			(stroke
				(width 0.3048)
				(type default)
			)
			(layer "F.SilkS")
		)
		(fp_arc
			(start -23.117556 1.803908)
			(mid -21.999956 0.686308)
			(end -20.882356 1.803908)
			(stroke
				(width 0.3048)
				(type default)
			)
			(layer "F.SilkS")
		)
		(fp_arc
			(start 20.882356 1.803908)
			(mid 21.999956 0.686308)
			(end 23.117556 1.803908)
			(stroke
				(width 0.3048)
				(type default)
			)
			(layer "F.SilkS")
		)
		(fp_poly
			(pts
				(xy -20.2184 11.7602) (xy -20.2184 4.4196) (xy -23.495 4.4196) (xy -23.495 0.2794) (xy -20.2184 0.2794)
				(xy -20.2184 -3.1496) (xy 20.2184 -3.1496) (xy 20.2184 0.2794) (xy 23.495 0.2794) (xy 23.495 4.4196)
				(xy 20.2184 4.4196) (xy 20.2184 11.7602) (xy 18.0975 11.7602) (xy 18.0975 10.0584) (xy -18.0975 10.0584)
				(xy -18.0975 11.7602)
			)
			(stroke
				(width 0)
				(type default)
			)
			(fill no)
			(layer "F.CrtYd")
		)
		(fp_poly
			(pts
				(xy -21.2471 16.256) (xy -21.2471 4.9276) (xy -24.003 4.9276) (xy -24.003 -0.2286) (xy -20.7264 -0.2286)
				(xy -20.7264 -3.6576) (xy 20.7264 -3.6576) (xy 20.7264 -0.2286) (xy 24.003 -0.2286) (xy 24.003 -0.00635)
				(xy 20.2184 -0.00635) (xy 20.2184 -3.1496) (xy -20.2184 -3.1496) (xy -20.2184 0.2794) (xy -23.495 0.2794)
				(xy -23.495 4.4196) (xy -20.2184 4.4196) (xy -20.2184 11.7602) (xy -18.0975 11.7602) (xy -18.0975 10.0584)
				(xy 18.0975 10.0584) (xy 18.0975 11.7602) (xy 20.2184 11.7602) (xy 20.2184 4.4196) (xy 23.495 4.4196)
				(xy 23.495 0.2794) (xy 20.2184 0.2794) (xy 20.2184 0.00635) (xy 24.003 0.00635) (xy 24.003 4.9276)
				(xy 21.2471 4.9276) (xy 21.2471 16.256)
			)
			(stroke
				(width 0)
				(type default)
			)
			(fill no)
			(layer "F.CrtYd")
		)
		(fp_poly
			(pts
				(xy -21.2471 16.256) (xy -21.2471 4.9276) (xy -24.003 4.9276) (xy -24.003 -0.2286) (xy -20.7264 -0.2286)
				(xy -20.7264 -3.6576) (xy 20.7264 -3.6576) (xy 20.7264 -0.2286) (xy 24.003 -0.2286) (xy 24.003 4.9276)
				(xy 21.2471 4.9276) (xy 21.2471 16.256)
			)
			(stroke
				(width 0)
				(type default)
			)
			(fill no)
			(layer "F.Fab")
		)
		(pad "" np_thru_hole circle
			(at -18.999962 0 270)
			(size 0.254 0.254)
			(drill 1.8542)
			(layers "*.Cu" "*.Mask")
			(clearance 1.1557)
			(thermal_gap 1.1557)
		)
		(pad "" np_thru_hole circle
			(at 18.999962 0 270)
			(size 0.254 0.254)
			(drill 1.8542)
			(layers "*.Cu" "*.Mask")
			(clearance 1.1557)
			(thermal_gap 1.1557)
		)
		(pad "E1" smd rect
			(at -7.079996 1.240028 270)
			(size 0.508 2.0066)
			(layers "F.Cu" "F.Mask" "F.Paste")
			(net "PE_CLK100M_DR10_2_P")
		)
		(pad "E2" smd rect
			(at -6.279896 1.240028 270)
			(size 0.508 2.0066)
			(layers "F.Cu" "F.Mask" "F.Paste")
			(net "PE_CLK100M_DR10_2_N")
		)
		(pad "E3" smd rect
			(at -5.48005 1.240028 270)
			(size 0.508 2.0066)
			(layers "F.Cu" "F.Mask" "F.Paste")
			(net "P3V3")
		)
		(pad "E4" smd rect
			(at -4.67995 1.240028 270)
			(size 0.508 2.0066)
			(layers "F.Cu" "F.Mask" "F.Paste")
			(net "SSD10_PERST_N")
		)
		(pad "E5" smd rect
			(at -3.880104 1.240028 270)
			(size 0.508 2.0066)
			(layers "F.Cu" "F.Mask" "F.Paste")
			(net "SSD10_PERST_N")
		)
		(pad "E6" smd rect
			(at -3.080004 1.240028 270)
			(size 0.508 2.0066)
			(layers "F.Cu" "F.Mask" "F.Paste")
			(net "Net_1287")
		)
		(pad "E7" smd rect
			(at -15.48003 -1.949958 270)
			(size 0.508 2.0066)
			(layers "F.Cu" "F.Mask" "F.Paste")
			(net "PE_CLK100M_DR10_1_P")
		)
		(pad "E8" smd rect
			(at -14.67993 -1.949958 270)
			(size 0.508 2.0066)
			(layers "F.Cu" "F.Mask" "F.Paste")
			(net "PE_CLK100M_DR10_1_N")
		)
		(pad "E9" smd rect
			(at -13.880084 -1.949958 270)
			(size 0.508 2.0066)
			(layers "F.Cu" "F.Mask" "F.Paste")
			(net "GND")
		)
		(pad "E10" smd rect
			(at -13.079984 -1.949958 270)
			(size 0.508 2.0066)
			(layers "F.Cu" "F.Mask" "F.Paste")
			(net "PE_TX1_DR10_P")
		)
		(pad "E11" smd rect
			(at -12.279884 -1.949958 270)
			(size 0.508 2.0066)
			(layers "F.Cu" "F.Mask" "F.Paste")
			(net "PE_TX1_DR10_N")
		)
		(pad "E12" smd rect
			(at -11.480038 -1.949958 270)
			(size 0.508 2.0066)
			(layers "F.Cu" "F.Mask" "F.Paste")
			(net "GND")
		)
		(pad "E13" smd rect
			(at -10.679938 -1.949958 270)
			(size 0.508 2.0066)
			(layers "F.Cu" "F.Mask" "F.Paste")
			(net "PE_RX1_DR10_P")
		)
		(pad "E14" smd rect
			(at -9.880092 -1.949958 270)
			(size 0.508 2.0066)
			(layers "F.Cu" "F.Mask" "F.Paste")
			(net "PE_RX1_DR10_N")
		)
		(pad "E15" smd rect
			(at -9.079992 -1.949958 270)
			(size 0.508 2.0066)
			(layers "F.Cu" "F.Mask" "F.Paste")
			(net "GND")
		)
		(pad "E16" smd rect
			(at -8.279892 -1.949958 270)
			(size 0.508 2.0066)
			(layers "F.Cu" "F.Mask" "F.Paste")
			(net "Net_1294")
		)
		(pad "E17" smd rect
			(at 9.320022 -1.949958 270)
			(size 0.508 2.0066)
			(layers "F.Cu" "F.Mask" "F.Paste")
			(net "PE_TX4_DR10_P")
		)
		(pad "E18" smd rect
			(at 10.120122 -1.949958 270)
			(size 0.508 2.0066)
			(layers "F.Cu" "F.Mask" "F.Paste")
			(net "PE_TX4_DR10_N")
		)
		(pad "E19" smd rect
			(at 10.919968 -1.949958 270)
			(size 0.508 2.0066)
			(layers "F.Cu" "F.Mask" "F.Paste")
			(net "GND")
		)
		(pad "E20" smd rect
			(at 11.720068 -1.949958 270)
			(size 0.508 2.0066)
			(layers "F.Cu" "F.Mask" "F.Paste")
			(net "PE_RX4_DR10_P")
		)
		(pad "E21" smd rect
			(at 12.519914 -1.949958 270)
			(size 0.508 2.0066)
			(layers "F.Cu" "F.Mask" "F.Paste")
			(net "PE_RX4_DR10_N")
		)
		(pad "E22" smd rect
			(at 13.320014 -1.949958 270)
			(size 0.508 2.0066)
			(layers "F.Cu" "F.Mask" "F.Paste")
			(net "GND")
		)
		(pad "E23" smd rect
			(at 14.120114 -1.949958 270)
			(size 0.508 2.0066)
			(layers "F.Cu" "F.Mask" "F.Paste")
			(net "SCL_DR10_R")
		)
		(pad "E24" smd rect
			(at 14.91996 -1.949958 270)
			(size 0.508 2.0066)
			(layers "F.Cu" "F.Mask" "F.Paste")
			(net "SDA_DR10_R")
		)
		(pad "E25" smd rect
			(at 15.72006 -1.949958 270)
			(size 0.508 2.0066)
			(layers "F.Cu" "F.Mask" "F.Paste")
			(net "DUALPORTEN#10")
		)
		(pad "P1" smd rect
			(at -1.905 0.824992 270)
			(size 0.6604 2.0574)
			(layers "F.Cu" "F.Mask" "F.Paste")
			(net "Net_1290")
		)
		(pad "P2" smd rect
			(at -0.635 0.824992 270)
			(size 0.6604 2.0574)
			(layers "F.Cu" "F.Mask" "F.Paste")
			(net "Net_1289")
		)
		(pad "P3" smd rect
			(at 0.635 0.824992 270)
			(size 0.6604 2.0574)
			(layers "F.Cu" "F.Mask" "F.Paste")
			(net "Net_1288")
		)
		(pad "P4" smd rect
			(at 1.905 0.824992 270)
			(size 0.6604 2.0574)
			(layers "F.Cu" "F.Mask" "F.Paste")
			(net "SSD10_CLK0_OE_N")
		)
		(pad "P5" smd rect
			(at 3.175 0.824992 270)
			(size 0.6604 2.0574)
			(layers "F.Cu" "F.Mask" "F.Paste")
			(net "GND")
		)
		(pad "P6" smd rect
			(at 4.445 0.824992 270)
			(size 0.6604 2.0574)
			(layers "F.Cu" "F.Mask" "F.Paste")
			(net "GND")
		)
		(pad "P7" smd rect
			(at 5.715 0.824992 270)
			(size 0.6604 2.0574)
			(layers "F.Cu" "F.Mask" "F.Paste")
			(net "Net_95")
		)
		(pad "P8" smd rect
			(at 6.985 0.824992 270)
			(size 0.6604 2.0574)
			(layers "F.Cu" "F.Mask" "F.Paste")
			(net "Net_67")
		)
		(pad "P9" smd rect
			(at 8.255 0.824992 270)
			(size 0.6604 2.0574)
			(layers "F.Cu" "F.Mask" "F.Paste")
			(net "Net_81")
		)
		(pad "P10" smd rect
			(at 9.525 0.824992 270)
			(size 0.6604 2.0574)
			(layers "F.Cu" "F.Mask" "F.Paste")
			(net "SSD_PRSNT_NET10")
		)
		(pad "P11" smd rect
			(at 10.795 0.824992 270)
			(size 0.6604 2.0574)
			(layers "F.Cu" "F.Mask" "F.Paste")
			(net "SSD_ACT_DR10")
		)
		(pad "P12" smd rect
			(at 12.065 0.824992 270)
			(size 0.6604 2.0574)
			(layers "F.Cu" "F.Mask" "F.Paste")
			(net "GND")
		)
		(pad "P13" smd rect
			(at 13.335 0.824992 270)
			(size 0.6604 2.0574)
			(layers "F.Cu" "F.Mask" "F.Paste")
			(net "12V_PRECH_SSD10")
		)
		(pad "P14" smd rect
			(at 14.605 0.824992 270)
			(size 0.6604 2.0574)
			(layers "F.Cu" "F.Mask" "F.Paste")
			(net "P12V_SSD10")
		)
		(pad "P15" smd rect
			(at 15.875 0.824992 270)
			(size 0.6604 2.0574)
			(layers "F.Cu" "F.Mask" "F.Paste")
			(net "P12V_SSD10")
		)
		(pad "PTH1" thru_hole oval
			(at -21.999956 2.350008 270)
			(size 1.524 2.6162)
			(drill oval 0.8128 1.905)
			(layers "*.Cu" "*.Mask")
			(remove_unused_layers no)
			(net "Net_1299")
			(clearance 0.1524)
			(thermal_gap 0.1524)
		)
		(pad "PTH2" thru_hole oval
			(at 21.999956 2.350008 270)
			(size 1.524 2.6162)
			(drill oval 0.8128 1.905)
			(layers "*.Cu" "*.Mask")
			(remove_unused_layers no)
			(net "Net_1283")
			(clearance 0.1524)
			(thermal_gap 0.1524)
		)
		(pad "S1" smd rect
			(at -15.875 0.824992 270)
			(size 0.6604 2.0574)
			(layers "F.Cu" "F.Mask" "F.Paste")
			(net "GND")
		)
		(pad "S2" smd rect
			(at -14.605 0.824992 270)
			(size 0.6604 2.0574)
			(layers "F.Cu" "F.Mask" "F.Paste")
			(net "Net_1298")
		)
		(pad "S3" smd rect
			(at -13.335 0.824992 270)
			(size 0.6604 2.0574)
			(layers "F.Cu" "F.Mask" "F.Paste")
			(net "Net_1297")
		)
		(pad "S4" smd rect
			(at -12.065 0.824992 270)
			(size 0.6604 2.0574)
			(layers "F.Cu" "F.Mask" "F.Paste")
			(net "GND")
		)
		(pad "S5" smd rect
			(at -10.795 0.824992 270)
			(size 0.6604 2.0574)
			(layers "F.Cu" "F.Mask" "F.Paste")
			(net "Net_1296")
		)
		(pad "S6" smd rect
			(at -9.525 0.824992 270)
			(size 0.6604 2.0574)
			(layers "F.Cu" "F.Mask" "F.Paste")
			(net "Net_1295")
		)
		(pad "S7" smd rect
			(at -8.255 0.824992 270)
			(size 0.6604 2.0574)
			(layers "F.Cu" "F.Mask" "F.Paste")
			(net "GND")
		)
		(pad "S8" smd rect
			(at -7.480046 -1.949958 270)
			(size 0.508 2.0066)
			(layers "F.Cu" "F.Mask" "F.Paste")
			(net "GND")
		)
		(pad "S9" smd rect
			(at -6.679946 -1.949958 270)
			(size 0.508 2.0066)
			(layers "F.Cu" "F.Mask" "F.Paste")
			(net "Net_1293")
		)
		(pad "S10" smd rect
			(at -5.8801 -1.949958 270)
			(size 0.508 2.0066)
			(layers "F.Cu" "F.Mask" "F.Paste")
			(net "Net_1292")
		)
		(pad "S11" smd rect
			(at -5.08 -1.949958 270)
			(size 0.508 2.0066)
			(layers "F.Cu" "F.Mask" "F.Paste")
			(net "GND")
		)
		(pad "S12" smd rect
			(at -4.2799 -1.949958 270)
			(size 0.508 2.0066)
			(layers "F.Cu" "F.Mask" "F.Paste")
			(net "Net_1291")
		)
		(pad "S13" smd rect
			(at -3.480054 -1.949958 270)
			(size 0.508 2.0066)
			(layers "F.Cu" "F.Mask" "F.Paste")
			(net "Net_1286")
		)
		(pad "S14" smd rect
			(at -2.679954 -1.949958 270)
			(size 0.508 2.0066)
			(layers "F.Cu" "F.Mask" "F.Paste")
			(net "GND")
		)
		(pad "S15" smd rect
			(at -1.880108 -1.949958 270)
			(size 0.508 2.0066)
			(layers "F.Cu" "F.Mask" "F.Paste")
			(net "Net_1285")
		)
		(pad "S16" smd rect
			(at -1.080008 -1.949958 270)
			(size 0.508 2.0066)
			(layers "F.Cu" "F.Mask" "F.Paste")
			(net "GND")
		)
		(pad "S17" smd rect
			(at -0.279908 -1.949958 270)
			(size 0.508 2.0066)
			(layers "F.Cu" "F.Mask" "F.Paste")
			(net "PE_TX2_DR10_P")
		)
		(pad "S18" smd rect
			(at 0.519938 -1.949958 270)
			(size 0.508 2.0066)
			(layers "F.Cu" "F.Mask" "F.Paste")
			(net "PE_TX2_DR10_N")
		)
		(pad "S19" smd rect
			(at 1.320038 -1.949958 270)
			(size 0.508 2.0066)
			(layers "F.Cu" "F.Mask" "F.Paste")
			(net "GND")
		)
		(pad "S20" smd rect
			(at 2.119884 -1.949958 270)
			(size 0.508 2.0066)
			(layers "F.Cu" "F.Mask" "F.Paste")
			(net "PE_RX2_DR10_P")
		)
		(pad "S21" smd rect
			(at 2.919984 -1.949958 270)
			(size 0.508 2.0066)
			(layers "F.Cu" "F.Mask" "F.Paste")
			(net "PE_RX2_DR10_N")
		)
		(pad "S22" smd rect
			(at 3.720084 -1.949958 270)
			(size 0.508 2.0066)
			(layers "F.Cu" "F.Mask" "F.Paste")
			(net "GND")
		)
		(pad "S23" smd rect
			(at 4.51993 -1.949958 270)
			(size 0.508 2.0066)
			(layers "F.Cu" "F.Mask" "F.Paste")
			(net "PE_TX3_DR10_P")
		)
		(pad "S24" smd rect
			(at 5.32003 -1.949958 270)
			(size 0.508 2.0066)
			(layers "F.Cu" "F.Mask" "F.Paste")
			(net "PE_TX3_DR10_N")
		)
		(pad "S25" smd rect
			(at 6.119876 -1.949958 270)
			(size 0.508 2.0066)
			(layers "F.Cu" "F.Mask" "F.Paste")
			(net "GND")
		)
		(pad "S26" smd rect
			(at 6.919976 -1.949958 270)
			(size 0.508 2.0066)
			(layers "F.Cu" "F.Mask" "F.Paste")
			(net "PE_RX3_DR10_P")
		)
		(pad "S27" smd rect
			(at 7.720076 -1.949958 270)
			(size 0.508 2.0066)
			(layers "F.Cu" "F.Mask" "F.Paste")
			(net "PE_RX3_DR10_N")
		)
		(pad "S28" smd rect
			(at 8.519922 -1.949958 270)
			(size 0.508 2.0066)
			(layers "F.Cu" "F.Mask" "F.Paste")
			(net "GND")
		)
		(zone
			(layers "F.Cu" "B.Cu" "In1.Cu" "In2.Cu" "In3.Cu" "In4.Cu" "In5.Cu" "In6.Cu")
			(hatch none 0.5)
			(connect_pads
				(clearance 0)
			)
			(min_thickness 0.25)
			(keepout
				(tracks not_allowed)
				(vias allowed)
				(pads allowed)
				(copperpour not_allowed)
				(footprints allowed)
			)
			(placement
				(enabled no)
				(sheetname "")
			)
			(fill
				(thermal_gap 0.5)
				(thermal_bridge_width 0.5)
				(island_removal_mode 0)
			)
			(polygon
				(pts
					(arc
						(start 22.081998 -457.330048)
						(mid 19.618198 -457.330048)
						(end 22.081998 -457.330048)
					)
				)
			)
		)
		(zone
			(layers "F.Cu" "B.Cu" "In1.Cu" "In2.Cu" "In3.Cu" "In4.Cu" "In5.Cu" "In6.Cu")
			(hatch none 0.5)
			(connect_pads
				(clearance 0)
			)
			(min_thickness 0.25)
			(keepout
				(tracks not_allowed)
				(vias allowed)
				(pads allowed)
				(copperpour not_allowed)
				(footprints allowed)
			)
			(placement
				(enabled no)
				(sheetname "")
			)
			(fill
				(thermal_gap 0.5)
				(thermal_bridge_width 0.5)
				(island_removal_mode 0)
			)
			(polygon
				(pts
					(arc
						(start 22.081998 -419.330124)
						(mid 19.618198 -419.330124)
						(end 22.081998 -419.330124)
					)
				)
			)
		)
	)
)
